(kicad_pcb
	(version 20260206)
	(generator "pcbnew")
	(generator_version "10.0")
	(general
		(thickness 1.6)
		(legacy_teardrops no)
	)
	(paper "A4")
	(title_block
		(title "panther-plus-userver — 13130-1b_20150205.brd")
		(comment 1 "Honey Badger (Wiwynn) / footprint 282 of 1509 (U13), pads 1-119 of 1283")
	)
	(layers
		(0 "F.Cu" signal "TOP")
		(4 "In1.Cu" signal "L2")
		(6 "In2.Cu" signal "L3")
		(8 "In3.Cu" signal "L4")
		(10 "In4.Cu" signal "L5")
		(12 "In5.Cu" signal "L6")
		(14 "In6.Cu" signal "L7")
		(16 "In7.Cu" signal "L8")
		(18 "In8.Cu" signal "L9")
		(20 "In9.Cu" signal "L10")
		(22 "In10.Cu" signal "L11")
		(2 "B.Cu" signal "BOTTOM")
		(9 "F.Adhes" user "F.Adhesive")
		(11 "B.Adhes" user "B.Adhesive")
		(13 "F.Paste" user "Package Geometry/Pastemask Top")
		(15 "B.Paste" user "Package Geometry/Pastemask Bottom")
		(5 "F.SilkS" user "Ref Des/Silkscreen Top")
		(7 "B.SilkS" user "Ref Des/Silkscreen Bottom")
		(1 "F.Mask" user "Board Geometry/Soldermask Top")
		(3 "B.Mask" user "Board Geometry/Soldermask Bottom")
		(17 "Dwgs.User" user "User.Drawings")
		(19 "Cmts.User" user "User.Comments")
		(21 "Eco1.User" user "User.Eco1")
		(23 "Eco2.User" user "User.Eco2")
		(25 "Edge.Cuts" user "Board Geometry/Outline")
		(27 "Margin" user)
		(31 "F.CrtYd" user "Package Geometry/Place Bound Top")
		(29 "B.CrtYd" user "Package Geometry/Place Bound Bottom")
		(35 "F.Fab" user "Ref Des/Assembly Top")
		(33 "B.Fab" user "Ref Des/Assembly Bottom")
	)
	(footprint ""
		(layer "F.Cu")
		(at 95.849948 -39.200074 180)
		(property "Reference" "U13"
			(at 0 0 180)
			(layer "F.SilkS")
			(hide yes)
			(effects
				(font
					(size 1.27 1.27)
				)
			)
		)
		(property "Value" "AVOTON-GP"
			(at -25.0317 -2.4892 180)
			(unlocked yes)
			(layer "F.Fab")
			(hide yes)
			(effects
				(font
					(size 1.016 1.016)
					(thickness 0.1524)
				)
			)
		)
		(property "Device Type" "BGA1283M3428-3H197"
			(at -25.0317 -4.0132 180)
			(unlocked yes)
			(layer "F.Fab")
			(hide yes)
			(effects
				(font
					(size 1.016 1.016)
					(thickness 0.1524)
				)
			)
		)
		(duplicate_pad_numbers_are_jumpers no)
		(pad "A5" smd circle
			(at -14.48562 -13.11148 180)
			(size 0.5588 0.5588)
			(layers "F.Cu" "F.Mask" "F.Paste")
			(net "GND")
		)
		(pad "A6" smd circle
			(at -13.67282 -13.11148 180)
			(size 0.4064 0.4064)
			(layers "F.Cu" "F.Mask" "F.Paste")
			(net "M_B_MON2_N")
		)
		(pad "A8" smd circle
			(at -12.86002 -13.11148 180)
			(size 0.4064 0.4064)
			(layers "F.Cu" "F.Mask" "F.Paste")
			(net "M_B_MON2_P")
		)
		(pad "A9" smd oval
			(at -12.17422 -13.24864 180)
			(size 0.254 0.3429)
			(layers "F.Cu" "F.Mask" "F.Paste")
			(net "GND")
		)
		(pad "A12" smd oval
			(at -10.54862 -13.24864 180)
			(size 0.254 0.3429)
			(layers "F.Cu" "F.Mask" "F.Paste")
			(net "GND")
		)
		(pad "A15" smd oval
			(at -9.10844 -13.24864 180)
			(size 0.254 0.3429)
			(layers "F.Cu" "F.Mask" "F.Paste")
			(net "GND")
		)
		(pad "A18" smd oval
			(at -7.6708 -13.24864 180)
			(size 0.254 0.3429)
			(layers "F.Cu" "F.Mask" "F.Paste")
			(net "GND")
		)
		(pad "A21" smd oval
			(at -6.0452 -13.24864 180)
			(size 0.254 0.3429)
			(layers "F.Cu" "F.Mask" "F.Paste")
			(net "M_B_DQS_DP2")
		)
		(pad "A24" smd oval
			(at -4.60756 -13.24864 180)
			(size 0.254 0.3429)
			(layers "F.Cu" "F.Mask" "F.Paste")
			(net "GND")
		)
		(pad "A27" smd oval
			(at -3.16738 -13.24864 180)
			(size 0.254 0.3429)
			(layers "F.Cu" "F.Mask" "F.Paste")
			(net "M_B_DQ10")
		)
		(pad "A30" smd oval
			(at -1.54178 -13.24864 180)
			(size 0.254 0.3429)
			(layers "F.Cu" "F.Mask" "F.Paste")
			(net "GND")
		)
		(pad "A33" smd oval
			(at -0.10414 -13.24864 180)
			(size 0.254 0.3429)
			(layers "F.Cu" "F.Mask" "F.Paste")
			(net "GND")
		)
		(pad "A36" smd oval
			(at 1.33604 -13.24864 180)
			(size 0.254 0.3429)
			(layers "F.Cu" "F.Mask" "F.Paste")
			(net "M_B_DQ6")
		)
		(pad "A39" smd oval
			(at 2.96164 -13.24864 180)
			(size 0.254 0.3429)
			(layers "F.Cu" "F.Mask" "F.Paste")
			(net "M_B_DQ4")
		)
		(pad "A42" smd oval
			(at 4.39928 -13.24864 180)
			(size 0.254 0.3429)
			(layers "F.Cu" "F.Mask" "F.Paste")
			(net "Net_1361")
		)
		(pad "A45" smd oval
			(at 5.83692 -13.24864 180)
			(size 0.254 0.3429)
			(layers "F.Cu" "F.Mask" "F.Paste")
			(net "GND")
		)
		(pad "A48" smd oval
			(at 7.46252 -13.24864 180)
			(size 0.254 0.3429)
			(layers "F.Cu" "F.Mask" "F.Paste")
			(net "GND")
		)
		(pad "A51" smd oval
			(at 8.9027 -13.24864 180)
			(size 0.254 0.3429)
			(layers "F.Cu" "F.Mask" "F.Paste")
			(net "GND")
		)
		(pad "A54" smd oval
			(at 10.34034 -13.24864 180)
			(size 0.254 0.3429)
			(layers "F.Cu" "F.Mask" "F.Paste")
			(net "Net_1348")
		)
		(pad "A57" smd oval
			(at 11.96594 -13.24864 180)
			(size 0.254 0.3429)
			(layers "F.Cu" "F.Mask" "F.Paste")
			(net "GND")
		)
		(pad "A59" smd circle
			(at 12.86002 -13.11148 180)
			(size 0.4064 0.4064)
			(layers "F.Cu" "F.Mask" "F.Paste")
			(net "GND")
		)
		(pad "A61" smd circle
			(at 13.67282 -13.11148 180)
			(size 0.4064 0.4064)
			(layers "F.Cu" "F.Mask" "F.Paste")
			(net "GND")
		)
		(pad "A62" smd circle
			(at 14.48562 -13.11148 180)
			(size 0.4064 0.4064)
			(layers "F.Cu" "F.Mask" "F.Paste")
			(net "GND")
		)
		(pad "A64" smd circle
			(at 15.29842 -13.11148 180)
			(size 0.5588 0.5588)
			(layers "F.Cu" "F.Mask" "F.Paste")
			(net "GND")
		)
		(pad "A66" smd circle
			(at 16.11122 -13.11148 180)
			(size 0.5588 0.5588)
			(layers "F.Cu" "F.Mask" "F.Paste")
			(net "GND")
		)
		(pad "AA3" smd circle
			(at -15.24762 -3.21564 180)
			(size 0.3048 0.3048)
			(layers "F.Cu" "F.Mask" "F.Paste")
			(net "GND")
		)
		(pad "AA5" smd circle
			(at -14.01318 -3.18516 180)
			(size 0.3048 0.3048)
			(layers "F.Cu" "F.Mask" "F.Paste")
			(net "GND")
		)
		(pad "AA21" smd circle
			(at -5.99948 -3.2004 180)
			(size 0.381 0.381)
			(layers "F.Cu" "F.Mask" "F.Paste")
			(net "P1V0")
		)
		(pad "AA23" smd circle
			(at -5.20192 -3.2004 180)
			(size 0.381 0.381)
			(layers "F.Cu" "F.Mask" "F.Paste")
			(net "GND")
		)
		(pad "AA25" smd circle
			(at -4.39928 -3.2004 180)
			(size 0.381 0.381)
			(layers "F.Cu" "F.Mask" "F.Paste")
			(net "GND")
		)
		(pad "AA26" smd circle
			(at -3.60172 -3.2004 180)
			(size 0.381 0.381)
			(layers "F.Cu" "F.Mask" "F.Paste")
			(net "GND")
		)
		(pad "AA28" smd circle
			(at -2.79908 -3.2004 180)
			(size 0.381 0.381)
			(layers "F.Cu" "F.Mask" "F.Paste")
			(net "GND")
		)
		(pad "AA29" smd circle
			(at -2.00152 -3.2004 180)
			(size 0.381 0.381)
			(layers "F.Cu" "F.Mask" "F.Paste")
			(net "GND")
		)
		(pad "AA31" smd circle
			(at -1.19888 -3.2004 180)
			(size 0.381 0.381)
			(layers "F.Cu" "F.Mask" "F.Paste")
			(net "GND")
		)
		(pad "AA32" smd circle
			(at -0.40132 -3.2004 180)
			(size 0.381 0.381)
			(layers "F.Cu" "F.Mask" "F.Paste")
			(net "P1V35")
		)
		(pad "AA34" smd circle
			(at 0.40132 -3.2004 180)
			(size 0.381 0.381)
			(layers "F.Cu" "F.Mask" "F.Paste")
			(net "P1V35")
		)
		(pad "AA36" smd circle
			(at 1.19888 -3.2004 180)
			(size 0.381 0.381)
			(layers "F.Cu" "F.Mask" "F.Paste")
			(net "GND")
		)
		(pad "AA38" smd circle
			(at 2.00152 -3.2004 180)
			(size 0.381 0.381)
			(layers "F.Cu" "F.Mask" "F.Paste")
			(net "P1V0_STBY")
		)
		(pad "AA39" smd circle
			(at 2.79908 -3.2004 180)
			(size 0.381 0.381)
			(layers "F.Cu" "F.Mask" "F.Paste")
			(net "P1V0_STBY")
		)
		(pad "AA41" smd circle
			(at 3.60172 -3.2004 180)
			(size 0.381 0.381)
			(layers "F.Cu" "F.Mask" "F.Paste")
			(net "P1V0_STBY")
		)
		(pad "AA42" smd circle
			(at 4.39928 -3.2004 180)
			(size 0.381 0.381)
			(layers "F.Cu" "F.Mask" "F.Paste")
			(net "GND")
		)
		(pad "AA44" smd circle
			(at 5.20192 -3.2004 180)
			(size 0.381 0.381)
			(layers "F.Cu" "F.Mask" "F.Paste")
			(net "GND")
		)
		(pad "AA46" smd circle
			(at 5.99948 -3.2004 180)
			(size 0.381 0.381)
			(layers "F.Cu" "F.Mask" "F.Paste")
			(net "XDP_SOC_CPU_TRST#")
		)
		(pad "AA47" smd circle
			(at 6.84276 -3.15722 180)
			(size 0.3048 0.3048)
			(layers "F.Cu" "F.Mask" "F.Paste")
			(net "Net_167")
		)
		(pad "AA62" smd circle
			(at 14.08176 -3.38836 180)
			(size 0.3048 0.3048)
			(layers "F.Cu" "F.Mask" "F.Paste")
			(net "GND")
		)
		(pad "AA64" smd circle
			(at 15.24254 -3.39852 180)
			(size 0.3048 0.3048)
			(layers "F.Cu" "F.Mask" "F.Paste")
			(net "GND")
		)
		(pad "AA66" smd oval
			(at 16.24838 -3.16738 180)
			(size 0.3429 0.254)
			(layers "F.Cu" "F.Mask" "F.Paste")
			(net "GND")
		)
		(pad "AB1" smd oval
			(at -16.24838 -2.96164 180)
			(size 0.3429 0.254)
			(layers "F.Cu" "F.Mask" "F.Paste")
			(net "GND")
		)
		(pad "AB2" smd circle
			(at -15.64132 -2.61112 180)
			(size 0.3048 0.3048)
			(layers "F.Cu" "F.Mask" "F.Paste")
			(net "M_B_DQ42")
		)
		(pad "AB4" smd circle
			(at -14.89964 -2.60604 180)
			(size 0.3048 0.3048)
			(layers "F.Cu" "F.Mask" "F.Paste")
			(net "M_B_DQ43")
		)
		(pad "AB5" smd circle
			(at -14.20368 -2.50698 180)
			(size 0.3048 0.3048)
			(layers "F.Cu" "F.Mask" "F.Paste")
			(net "GND")
		)
		(pad "AB20" smd circle
			(at -6.84276 -2.91592 180)
			(size 0.3048 0.3048)
			(layers "F.Cu" "F.Mask" "F.Paste")
			(net "GND")
		)
		(pad "AB62" smd circle
			(at 14.20368 -2.69494 180)
			(size 0.3048 0.3048)
			(layers "F.Cu" "F.Mask" "F.Paste")
			(net "SPI_CPU_MOSI")
		)
		(pad "AB63" smd circle
			(at 14.89964 -2.78638 180)
			(size 0.3048 0.3048)
			(layers "F.Cu" "F.Mask" "F.Paste")
			(net "PU_PMU_GPE#")
		)
		(pad "AB65" smd circle
			(at 15.63878 -2.8194 180)
			(size 0.3048 0.3048)
			(layers "F.Cu" "F.Mask" "F.Paste")
			(net "SUS_STAT#")
		)
		(pad "AC8" smd circle
			(at -12.96416 -2.21742 180)
			(size 0.3048 0.3048)
			(layers "F.Cu" "F.Mask" "F.Paste")
			(net "M_B_DQ56")
		)
		(pad "AC9" smd circle
			(at -12.20216 -2.21742 180)
			(size 0.3048 0.3048)
			(layers "F.Cu" "F.Mask" "F.Paste")
			(net "M_B_DQ61")
		)
		(pad "AC11" smd circle
			(at -11.44016 -2.21742 180)
			(size 0.3048 0.3048)
			(layers "F.Cu" "F.Mask" "F.Paste")
			(net "M_B_DQ60")
		)
		(pad "AC12" smd circle
			(at -10.67816 -2.21742 180)
			(size 0.3048 0.3048)
			(layers "F.Cu" "F.Mask" "F.Paste")
			(net "GND")
		)
		(pad "AC14" smd circle
			(at -9.91616 -2.21742 180)
			(size 0.3048 0.3048)
			(layers "F.Cu" "F.Mask" "F.Paste")
			(net "M_B_DQ62")
		)
		(pad "AC15" smd circle
			(at -9.15416 -2.21742 180)
			(size 0.3048 0.3048)
			(layers "F.Cu" "F.Mask" "F.Paste")
			(net "M_B_DQ63")
		)
		(pad "AC17" smd circle
			(at -8.39216 -2.21742 180)
			(size 0.3048 0.3048)
			(layers "F.Cu" "F.Mask" "F.Paste")
			(net "M_B_DQ59")
		)
		(pad "AC18" smd circle
			(at -7.63016 -2.21742 180)
			(size 0.3048 0.3048)
			(layers "F.Cu" "F.Mask" "F.Paste")
			(net "GND")
		)
		(pad "AC20" smd circle
			(at -6.92912 -2.21742 180)
			(size 0.3048 0.3048)
			(layers "F.Cu" "F.Mask" "F.Paste")
			(net "GND")
		)
		(pad "AC21" smd circle
			(at -5.99948 -2.4003 180)
			(size 0.381 0.381)
			(layers "F.Cu" "F.Mask" "F.Paste")
			(net "GND")
		)
		(pad "AC23" smd circle
			(at -5.20192 -2.4003 180)
			(size 0.381 0.381)
			(layers "F.Cu" "F.Mask" "F.Paste")
			(net "GND")
		)
		(pad "AC25" smd circle
			(at -4.39928 -2.4003 180)
			(size 0.381 0.381)
			(layers "F.Cu" "F.Mask" "F.Paste")
			(net "TP_CPU_RSVD12")
		)
		(pad "AC26" smd circle
			(at -3.60172 -2.4003 180)
			(size 0.381 0.381)
			(layers "F.Cu" "F.Mask" "F.Paste")
			(net "TP_CPU_RSVD11")
		)
		(pad "AC28" smd circle
			(at -2.79908 -2.4003 180)
			(size 0.381 0.381)
			(layers "F.Cu" "F.Mask" "F.Paste")
			(net "GND")
		)
		(pad "AC29" smd circle
			(at -2.00152 -2.4003 180)
			(size 0.381 0.381)
			(layers "F.Cu" "F.Mask" "F.Paste")
			(net "GND")
		)
		(pad "AC31" smd circle
			(at -1.19888 -2.4003 180)
			(size 0.381 0.381)
			(layers "F.Cu" "F.Mask" "F.Paste")
			(net "GND")
		)
		(pad "AC32" smd circle
			(at -0.40132 -2.4003 180)
			(size 0.381 0.381)
			(layers "F.Cu" "F.Mask" "F.Paste")
			(net "GND")
		)
		(pad "AC34" smd circle
			(at 0.40132 -2.4003 180)
			(size 0.381 0.381)
			(layers "F.Cu" "F.Mask" "F.Paste")
			(net "GND")
		)
		(pad "AC36" smd circle
			(at 1.19888 -2.4003 180)
			(size 0.381 0.381)
			(layers "F.Cu" "F.Mask" "F.Paste")
			(net "GND")
		)
		(pad "AC38" smd circle
			(at 2.00152 -2.4003 180)
			(size 0.381 0.381)
			(layers "F.Cu" "F.Mask" "F.Paste")
			(net "P1V0_STBY")
		)
		(pad "AC39" smd circle
			(at 2.79908 -2.4003 180)
			(size 0.381 0.381)
			(layers "F.Cu" "F.Mask" "F.Paste")
			(net "P1V0_STBY")
		)
		(pad "AC41" smd circle
			(at 3.60172 -2.4003 180)
			(size 0.381 0.381)
			(layers "F.Cu" "F.Mask" "F.Paste")
			(net "P1V0_STBY")
		)
		(pad "AC42" smd circle
			(at 4.39928 -2.4003 180)
			(size 0.381 0.381)
			(layers "F.Cu" "F.Mask" "F.Paste")
			(net "P1V0_STBY")
		)
		(pad "AC44" smd circle
			(at 5.20192 -2.4003 180)
			(size 0.381 0.381)
			(layers "F.Cu" "F.Mask" "F.Paste")
			(net "P1V0_STBY")
		)
		(pad "AC46" smd circle
			(at 5.99948 -2.4003 180)
			(size 0.381 0.381)
			(layers "F.Cu" "F.Mask" "F.Paste")
			(net "GND")
		)
		(pad "AC47" smd circle
			(at 6.92912 -2.45618 180)
			(size 0.3048 0.3048)
			(layers "F.Cu" "F.Mask" "F.Paste")
			(net "CPU_RSMRST_R#")
		)
		(pad "AC49" smd circle
			(at 7.63016 -2.45618 180)
			(size 0.3048 0.3048)
			(layers "F.Cu" "F.Mask" "F.Paste")
			(net "PMU_PWRBTN_R#")
		)
		(pad "AC50" smd circle
			(at 8.39216 -2.45618 180)
			(size 0.3048 0.3048)
			(layers "F.Cu" "F.Mask" "F.Paste")
			(net "GND")
		)
		(pad "AC52" smd circle
			(at 9.15416 -2.45618 180)
			(size 0.3048 0.3048)
			(layers "F.Cu" "F.Mask" "F.Paste")
			(net "PMU_SLP_DDRVTT#")
		)
		(pad "AC53" smd circle
			(at 9.91616 -2.45618 180)
			(size 0.3048 0.3048)
			(layers "F.Cu" "F.Mask" "F.Paste")
			(net "XDP_SOC_CPU_TMS")
		)
		(pad "AC55" smd circle
			(at 10.67816 -2.45618 180)
			(size 0.3048 0.3048)
			(layers "F.Cu" "F.Mask" "F.Paste")
			(net "GND")
		)
		(pad "AC56" smd circle
			(at 11.44016 -2.45618 180)
			(size 0.3048 0.3048)
			(layers "F.Cu" "F.Mask" "F.Paste")
			(net "XDP_SOC_CPU_TDI")
		)
		(pad "AC58" smd circle
			(at 12.20216 -2.45618 180)
			(size 0.3048 0.3048)
			(layers "F.Cu" "F.Mask" "F.Paste")
			(net "CPU_FPGA_DISABLE")
		)
		(pad "AC59" smd circle
			(at 12.96416 -2.45618 180)
			(size 0.3048 0.3048)
			(layers "F.Cu" "F.Mask" "F.Paste")
			(net "GND")
		)
		(pad "AD2" smd circle
			(at -15.63878 -1.68402 180)
			(size 0.3048 0.3048)
			(layers "F.Cu" "F.Mask" "F.Paste")
			(net "GND")
		)
		(pad "AD4" smd circle
			(at -14.89964 -1.71704 180)
			(size 0.3048 0.3048)
			(layers "F.Cu" "F.Mask" "F.Paste")
			(net "GND")
		)
		(pad "AD5" smd circle
			(at -14.20368 -1.80848 180)
			(size 0.3048 0.3048)
			(layers "F.Cu" "F.Mask" "F.Paste")
			(net "GND")
		)
		(pad "AD8" smd circle
			(at -12.96416 -1.51638 180)
			(size 0.3048 0.3048)
			(layers "F.Cu" "F.Mask" "F.Paste")
			(net "M_B_DQ57")
		)
		(pad "AD9" smd circle
			(at -12.20216 -1.51638 180)
			(size 0.3048 0.3048)
			(layers "F.Cu" "F.Mask" "F.Paste")
			(net "GND")
		)
		(pad "AD11" smd circle
			(at -11.44016 -1.51638 180)
			(size 0.3048 0.3048)
			(layers "F.Cu" "F.Mask" "F.Paste")
			(net "M_B_DQS_DN7")
		)
		(pad "AD12" smd circle
			(at -10.67816 -1.51638 180)
			(size 0.3048 0.3048)
			(layers "F.Cu" "F.Mask" "F.Paste")
			(net "M_B_DQS_DP7")
		)
		(pad "AD14" smd circle
			(at -9.91616 -1.51638 180)
			(size 0.3048 0.3048)
			(layers "F.Cu" "F.Mask" "F.Paste")
			(net "GND")
		)
		(pad "AD15" smd circle
			(at -9.15416 -1.51638 180)
			(size 0.3048 0.3048)
			(layers "F.Cu" "F.Mask" "F.Paste")
			(net "M_B_DQ58")
		)
		(pad "AD17" smd circle
			(at -8.39216 -1.51638 180)
			(size 0.3048 0.3048)
			(layers "F.Cu" "F.Mask" "F.Paste")
			(net "GND")
		)
		(pad "AD18" smd circle
			(at -7.63016 -1.51638 180)
			(size 0.3048 0.3048)
			(layers "F.Cu" "F.Mask" "F.Paste")
			(net "GND")
		)
		(pad "AD20" smd circle
			(at -6.92912 -1.51638 180)
			(size 0.3048 0.3048)
			(layers "F.Cu" "F.Mask" "F.Paste")
			(net "GND")
		)
		(pad "AD21" smd circle
			(at -5.99948 -1.6002 180)
			(size 0.381 0.381)
			(layers "F.Cu" "F.Mask" "F.Paste")
			(net "PVCCP")
		)
		(pad "AD23" smd circle
			(at -5.20192 -1.6002 180)
			(size 0.381 0.381)
			(layers "F.Cu" "F.Mask" "F.Paste")
			(net "PVCCP")
		)
		(pad "AD25" smd circle
			(at -4.39928 -1.6002 180)
			(size 0.381 0.381)
			(layers "F.Cu" "F.Mask" "F.Paste")
			(net "PVCCP")
		)
		(pad "AD26" smd circle
			(at -3.60172 -1.6002 180)
			(size 0.381 0.381)
			(layers "F.Cu" "F.Mask" "F.Paste")
			(net "PVCCP")
		)
		(pad "AD28" smd circle
			(at -2.79908 -1.6002 180)
			(size 0.381 0.381)
			(layers "F.Cu" "F.Mask" "F.Paste")
			(net "P1V0")
		)
		(pad "AD29" smd circle
			(at -2.00152 -1.6002 180)
			(size 0.381 0.381)
			(layers "F.Cu" "F.Mask" "F.Paste")
			(net "P1V0")
		)
		(pad "AD31" smd circle
			(at -1.19888 -1.6002 180)
			(size 0.381 0.381)
			(layers "F.Cu" "F.Mask" "F.Paste")
			(net "P1V1")
		)
		(pad "AD32" smd circle
			(at -0.40132 -1.6002 180)
			(size 0.381 0.381)
			(layers "F.Cu" "F.Mask" "F.Paste")
			(net "P1V1")
		)
		(pad "AD34" smd circle
			(at 0.40132 -1.6002 180)
			(size 0.381 0.381)
			(layers "F.Cu" "F.Mask" "F.Paste")
			(net "GND")
		)
		(pad "AD36" smd circle
			(at 1.19888 -1.6002 180)
			(size 0.381 0.381)
			(layers "F.Cu" "F.Mask" "F.Paste")
			(net "PVNN")
		)
		(pad "AD38" smd circle
			(at 2.00152 -1.6002 180)
			(size 0.381 0.381)
			(layers "F.Cu" "F.Mask" "F.Paste")
			(net "P1V0")
		)
		(pad "AD39" smd circle
			(at 2.79908 -1.6002 180)
			(size 0.381 0.381)
			(layers "F.Cu" "F.Mask" "F.Paste")
			(net "PVNN")
		)
		(pad "AD41" smd circle
			(at 3.60172 -1.6002 180)
			(size 0.381 0.381)
			(layers "F.Cu" "F.Mask" "F.Paste")
			(net "GND")
		)
		(pad "AD42" smd circle
			(at 4.39928 -1.6002 180)
			(size 0.381 0.381)
			(layers "F.Cu" "F.Mask" "F.Paste")
			(net "P3V3_CPU")
		)
		(pad "AD44" smd circle
			(at 5.20192 -1.6002 180)
			(size 0.381 0.381)
			(layers "F.Cu" "F.Mask" "F.Paste")
			(net "P3V3_CPU")
		)
		(pad "AD46" smd circle
			(at 5.99948 -1.6002 180)
			(size 0.381 0.381)
			(layers "F.Cu" "F.Mask" "F.Paste")
			(net "GND")
		)
		(pad "AD47" smd circle
			(at 6.92912 -1.75514 180)
			(size 0.3048 0.3048)
			(layers "F.Cu" "F.Mask" "F.Paste")
			(net "GND")
		)
		(pad "AD49" smd circle
			(at 7.63016 -1.75514 180)
			(size 0.3048 0.3048)
			(layers "F.Cu" "F.Mask" "F.Paste")
			(net "SRTCRST_R#")
		)
	)
)
